# S9S_MB_2U (Grand Teton) — schematic netlist excerpt (pin names and nets, part order shuffled) for the footprints in the layout excerpt that follows; sources: Cadence DE-HDL packaged netlist, KiCad conversion of 03242023_DA0F0TMBIJ0_F0T_Motherboard_J_brd_V01_OCP.brd

PC1204_P1_3  Q_CAP  1UF 16V 10% X6S  pkg C0402  page 290 : A = PVCCFA_EHV_FIVRA_CPU1 ; B = GND
R2409  Q_RES  10K 1% CHIP  pkg 0402LF  page 282 : A = P3V3_AUX ; B = PWRGD_PVNN_MAIN_CPU0_R
PC567_P1_1  Q_CAP  22UF 16V 20% X6S  pkg C0805  page 285 : A = SW_P12V_PVCCIN_CPU1_FLT ; B = GND

(kicad_pcb
	(version 20260206)
	(generator "pcbnew")
	(generator_version "10.0")
	(general
		(thickness 1.6)
		(legacy_teardrops no)
	)
	(paper "A4")
	(title_block
		(title "03242023_DA0F0TMBIJ0_F0T_Motherboard_J_brd_V01_OCP.brd")
		(comment 1 "Grand Teton / footprints 4900-4902 of 6105")
	)
	(layers
		(0 "F.Cu" signal "TOP")
		(4 "In1.Cu" signal "GND")
		(6 "In2.Cu" signal "IN1")
		(8 "In3.Cu" signal "GND1")
		(10 "In4.Cu" signal "IN2")
		(12 "In5.Cu" signal "GND2")
		(14 "In6.Cu" signal "IN3")
		(16 "In7.Cu" signal "GND3")
		(18 "In8.Cu" signal "VCC")
		(20 "In9.Cu" signal "VCC1")
		(22 "In10.Cu" signal "GND4")
		(24 "In11.Cu" signal "IN4")
		(26 "In12.Cu" signal "GND5")
		(28 "In13.Cu" signal "IN5")
		(30 "In14.Cu" signal "GND6")
		(32 "In15.Cu" signal "IN6")
		(34 "In16.Cu" signal "GND7")
		(2 "B.Cu" signal "BOTTOM")
		(9 "F.Adhes" user "F.Adhesive")
		(11 "B.Adhes" user "B.Adhesive")
		(13 "F.Paste" user "Package Geometry/Pastemask Top")
		(15 "B.Paste" user "Package Geometry/Pastemask Bottom")
		(5 "F.SilkS" user "Ref Des/Silkscreen Top")
		(7 "B.SilkS" user "Ref Des/Silkscreen Bottom")
		(1 "F.Mask" user "Board Geometry/Soldermask Top")
		(3 "B.Mask" user "Board Geometry/Soldermask Bottom")
		(17 "Dwgs.User" user "User.Drawings")
		(19 "Cmts.User" user "User.Comments")
		(21 "Eco1.User" user "User.Eco1")
		(23 "Eco2.User" user "User.Eco2")
		(25 "Edge.Cuts" user "Board Geometry/Outline")
		(27 "Margin" user)
		(31 "F.CrtYd" user "Package Geometry/Place Bound Top")
		(29 "B.CrtYd" user "Package Geometry/Place Bound Bottom")
		(35 "F.Fab" user "Ref Des/Assembly Top")
		(33 "B.Fab" user "Ref Des/Assembly Bottom")
	)
	(footprint ""
		(layer "B.Cu")
		(at 184.962546 -344.733626 -90)
		(property "Reference" "PC1204_P1_3"
			(at 0 0 90)
			(layer "B.SilkS")
			(hide yes)
			(effects
				(font
					(size 1.27 1.27)
				)
				(justify mirror)
			)
		)
		(property "Value" ""
			(at 0 0 90)
			(layer "B.Fab")
			(effects
				(font
					(size 1.27 1.27)
				)
				(justify mirror)
			)
		)
		(duplicate_pad_numbers_are_jumpers no)
		(fp_line
			(start -0.7874 0.4064)
			(end 0.7874 0.4064)
			(stroke
				(width 0.1524)
				(type default)
			)
			(layer "B.SilkS")
		)
		(fp_line
			(start 0.7874 0.4064)
			(end 0.7874 -0.4064)
			(stroke
				(width 0.1524)
				(type default)
			)
			(layer "B.SilkS")
		)
		(fp_line
			(start -0.7874 -0.4064)
			(end -0.7874 0.4064)
			(stroke
				(width 0.1524)
				(type default)
			)
			(layer "B.SilkS")
		)
		(fp_line
			(start 0.7874 -0.4064)
			(end -0.7874 -0.4064)
			(stroke
				(width 0.1524)
				(type default)
			)
			(layer "B.SilkS")
		)
		(fp_line
			(start -0.67945 0.3048)
			(end -0.120396 0.3048)
			(stroke
				(width 0.1)
				(type default)
			)
			(layer "B.Fab")
		)
		(fp_line
			(start -0.120396 0.3048)
			(end -0.120396 0.2794)
			(stroke
				(width 0.1)
				(type default)
			)
			(layer "B.Fab")
		)
		(fp_line
			(start 0.12065 0.3048)
			(end 0.67945 0.3048)
			(stroke
				(width 0.1)
				(type default)
			)
			(layer "B.Fab")
		)
		(fp_line
			(start 0.67945 0.3048)
			(end 0.67945 -0.305054)
			(stroke
				(width 0.1)
				(type default)
			)
			(layer "B.Fab")
		)
		(fp_line
			(start -0.120396 0.2794)
			(end 0.12065 0.2794)
			(stroke
				(width 0.1)
				(type default)
			)
			(layer "B.Fab")
		)
		(fp_line
			(start 0.12065 0.2794)
			(end 0.12065 0.3048)
			(stroke
				(width 0.1)
				(type default)
			)
			(layer "B.Fab")
		)
		(fp_line
			(start -0.12065 -0.2794)
			(end -0.12065 -0.3048)
			(stroke
				(width 0.1)
				(type default)
			)
			(layer "B.Fab")
		)
		(fp_line
			(start 0.12065 -0.2794)
			(end -0.12065 -0.2794)
			(stroke
				(width 0.1)
				(type default)
			)
			(layer "B.Fab")
		)
		(fp_line
			(start -0.67945 -0.3048)
			(end -0.67945 0.3048)
			(stroke
				(width 0.1)
				(type default)
			)
			(layer "B.Fab")
		)
		(fp_line
			(start -0.12065 -0.3048)
			(end -0.67945 -0.3048)
			(stroke
				(width 0.1)
				(type default)
			)
			(layer "B.Fab")
		)
		(fp_line
			(start 0.12065 -0.305054)
			(end 0.12065 -0.2794)
			(stroke
				(width 0.1)
				(type default)
			)
			(layer "B.Fab")
		)
		(fp_line
			(start 0.67945 -0.305054)
			(end 0.12065 -0.305054)
			(stroke
				(width 0.1)
				(type default)
			)
			(layer "B.Fab")
		)
		(pad "1" smd circle
			(at 0.40005 0 90)
			(size 0 0)
			(layers "B.Cu" "B.Mask" "B.Paste")
			(net "PVCCFA_EHV_FIVRA_CPU1")
		)
		(pad "2" smd circle
			(at -0.40005 0 90)
			(size 0 0)
			(layers "B.Cu" "B.Mask" "B.Paste")
			(net "GND")
		)
	)
	(footprint ""
		(layer "B.Cu")
		(at 435.255924 -180.958998 90)
		(property "Reference" "R2409"
			(at 0 0 90)
			(layer "B.SilkS")
			(hide yes)
			(effects
				(font
					(size 1.27 1.27)
				)
				(justify mirror)
			)
		)
		(property "Value" ""
			(at 0 0 90)
			(layer "B.Fab")
			(effects
				(font
					(size 1.27 1.27)
				)
				(justify mirror)
			)
		)
		(duplicate_pad_numbers_are_jumpers no)
		(fp_line
			(start 0.7874 -0.4064)
			(end -0.7874 -0.4064)
			(stroke
				(width 0.1524)
				(type default)
			)
			(layer "B.SilkS")
		)
		(fp_line
			(start -0.7874 -0.4064)
			(end -0.7874 0.4064)
			(stroke
				(width 0.1524)
				(type default)
			)
			(layer "B.SilkS")
		)
		(fp_line
			(start 0.7874 0.4064)
			(end 0.7874 -0.4064)
			(stroke
				(width 0.1524)
				(type default)
			)
			(layer "B.SilkS")
		)
		(fp_line
			(start -0.7874 0.4064)
			(end 0.7874 0.4064)
			(stroke
				(width 0.1524)
				(type default)
			)
			(layer "B.SilkS")
		)
		(fp_line
			(start 0.67945 -0.305054)
			(end 0.12065 -0.305054)
			(stroke
				(width 0.1)
				(type default)
			)
			(layer "B.Fab")
		)
		(fp_line
			(start 0.12065 -0.305054)
			(end 0.12065 -0.2794)
			(stroke
				(width 0.1)
				(type default)
			)
			(layer "B.Fab")
		)
		(fp_line
			(start -0.12065 -0.3048)
			(end -0.67945 -0.3048)
			(stroke
				(width 0.1)
				(type default)
			)
			(layer "B.Fab")
		)
		(fp_line
			(start -0.67945 -0.3048)
			(end -0.67945 0.3048)
			(stroke
				(width 0.1)
				(type default)
			)
			(layer "B.Fab")
		)
		(fp_line
			(start 0.12065 -0.2794)
			(end -0.12065 -0.2794)
			(stroke
				(width 0.1)
				(type default)
			)
			(layer "B.Fab")
		)
		(fp_line
			(start -0.12065 -0.2794)
			(end -0.12065 -0.3048)
			(stroke
				(width 0.1)
				(type default)
			)
			(layer "B.Fab")
		)
		(fp_line
			(start 0.12065 0.2794)
			(end 0.12065 0.3048)
			(stroke
				(width 0.1)
				(type default)
			)
			(layer "B.Fab")
		)
		(fp_line
			(start -0.120396 0.2794)
			(end 0.12065 0.2794)
			(stroke
				(width 0.1)
				(type default)
			)
			(layer "B.Fab")
		)
		(fp_line
			(start 0.67945 0.3048)
			(end 0.67945 -0.305054)
			(stroke
				(width 0.1)
				(type default)
			)
			(layer "B.Fab")
		)
		(fp_line
			(start 0.12065 0.3048)
			(end 0.67945 0.3048)
			(stroke
				(width 0.1)
				(type default)
			)
			(layer "B.Fab")
		)
		(fp_line
			(start -0.120396 0.3048)
			(end -0.120396 0.2794)
			(stroke
				(width 0.1)
				(type default)
			)
			(layer "B.Fab")
		)
		(fp_line
			(start -0.67945 0.3048)
			(end -0.120396 0.3048)
			(stroke
				(width 0.1)
				(type default)
			)
			(layer "B.Fab")
		)
		(pad "1" smd circle
			(at 0.40005 0 270)
			(size 0 0)
			(layers "B.Cu" "B.Mask" "B.Paste")
			(net "P3V3_AUX")
		)
		(pad "2" smd circle
			(at -0.40005 0 270)
			(size 0 0)
			(layers "B.Cu" "B.Mask" "B.Paste")
			(net "PWRGD_PVNN_MAIN_CPU0_R")
		)
	)
	(footprint ""
		(layer "B.Cu")
		(at 100.195126 -333.639922 90)
		(property "Reference" "PC567_P1_1"
			(at 0 0 90)
			(layer "B.SilkS")
			(hide yes)
			(effects
				(font
					(size 1.27 1.27)
				)
				(justify mirror)
			)
		)
		(property "Value" ""
			(at 0 0 90)
			(layer "B.Fab")
			(effects
				(font
					(size 1.27 1.27)
				)
				(justify mirror)
			)
		)
		(duplicate_pad_numbers_are_jumpers no)
		(fp_line
			(start 1.524 -0.762)
			(end -1.524 -0.762)
			(stroke
				(width 0.1524)
				(type default)
			)
			(layer "B.SilkS")
		)
		(fp_line
			(start -1.524 -0.762)
			(end -1.524 0.762)
			(stroke
				(width 0.1524)
				(type default)
			)
			(layer "B.SilkS")
		)
		(fp_line
			(start 1.524 0.762)
			(end 1.524 -0.762)
			(stroke
				(width 0.1524)
				(type default)
			)
			(layer "B.SilkS")
		)
		(fp_line
			(start -1.524 0.762)
			(end 1.524 0.762)
			(stroke
				(width 0.1524)
				(type default)
			)
			(layer "B.SilkS")
		)
		(fp_line
			(start 1.1049 -0.724916)
			(end 1.1049 0.724916)
			(stroke
				(width 0.1)
				(type default)
			)
			(layer "B.Fab")
		)
		(fp_line
			(start -1.1049 -0.724916)
			(end 1.1049 -0.724916)
			(stroke
				(width 0.1)
				(type default)
			)
			(layer "B.Fab")
		)
		(fp_line
			(start 1.1049 0.724916)
			(end -1.1049 0.724916)
			(stroke
				(width 0.1)
				(type default)
			)
			(layer "B.Fab")
		)
		(fp_line
			(start -1.1049 0.724916)
			(end -1.1049 -0.724916)
			(stroke
				(width 0.1)
				(type default)
			)
			(layer "B.Fab")
		)
		(pad "1" smd rect
			(at 0.889 0 90)
			(size 1.016 1.27)
			(layers "B.Cu" "B.Mask" "B.Paste")
			(net "SW_P12V_PVCCIN_CPU1_FLT")
		)
		(pad "2" smd rect
			(at -0.889 0 90)
			(size 1.016 1.27)
			(layers "B.Cu" "B.Mask" "B.Paste")
			(net "GND")
		)
	)
)
